FILE_TYPE = MACRO_DRAWING;
SET COLOR_WIRE YELLOW;
SET COLOR_PROP ORANGE;
SET COLOR_DOT WHITE;
SET COLOR_ARC YELLOW;
SET COLOR_BODY GREEN;
SET COLOR_NOTE PURPLE;
SET PROP_DISPLAY VALUE;
SET PAGE_NUMBER P138;
FORCEADD QUANTA_TITLE_BLOCK_C..1
(13550 -2900);
FORCEPROP 1 LAST CUSTOM_TXT_CDS <NAME_2>
J 0
(10375 -2850);
FORCEPROP 1 LAST CUSTOM_TXT_CDS <NAME_1>
J 0
(10375 -2725);
FORCEPROP 1 LAST CUSTOM_TXT_CDS <Q_PROJ>
J 0
(11168 -2798);
DISPLAY 1.212766 (11168 -2798);
FORCEPROP 1 LAST CUSTOM_TXT_CDS <Q_REV>
J 0
(13366 -2797);
DISPLAY 1.212766 (13366 -2797);
FORCEPROP 1 LAST CUSTOM_TXT_CDS <CON_LAST_MODIFIED>
J 0
(11665 -2885);
DISPLAY 0.978723 (11665 -2885);
FORCEPROP 1 LAST CUSTOM_TXT_CDS <CON_PAGE_NUM> OF <CON_TOTAL_PAGES>
J 0
(13104 -2882);
DISPLAY 0.978723 (13104 -2882);
FORCEPROP 1 LAST Q_TITLE BLANK
J 0
(4184 -2874);
DISPLAY 1.957447 (4184 -2874);
PAINT GREEN (4184 -2874);
FORCEPROP 2 LAST CUSTOM_TXT_CDS <Q_NUMBER>
J 0
(12147 -2797);
DISPLAY 1.212766 (12147 -2797);
FORCEPROP 1 LAST Q_DEPT 
J 1
(9787 -2851);
DISPLAY 1.957447 (9787 -2851);
PAINT GREEN (9787 -2851);
FORCEPROP 2 LAST CDS_XR_PAGE_TITLE CR-135 : @S9S_MB_2U_LIB.S9S_MB_2U(SCH_1):PAGE135
J 0
(5660 2350);
DISPLAY 0.638298 (5660 2350);
PAINT PINK (5660 2350);
DISPLAY INVISIBLE (5660 2350);
FORCEPROP 2 LAST PAGE_BORDER TRUE
J 0
(5660 2350);
DISPLAY 0.638298 (5660 2350);
PAINT PINK (5660 2350);
DISPLAY INVISIBLE (5660 2350);
FORCEPROP 1 LAST COMMENT_BODY TRUE
J 0
(13562 -2913);
DISPLAY 0.978723 (13562 -2913);
PAINT GREEN (13562 -2913);
DISPLAY INVISIBLE (13562 -2913);
FORCEPROP 1 LAST CDS_LMAN_SYM_OUTLINE -9475,6775,100,-125
J 0
(13550 -2900);
DISPLAY 0.468085 (13550 -2900);
PAINT GREEN (13550 -2900);
DISPLAY INVISIBLE (13550 -2900);
FORCEPROP 2 LAST CDS_LIB pure_quanta
J 0
(13550 -2900);
PAINT MONO (13550 -2900);
DISPLAY INVISIBLE (13550 -2900);
FORCEPROP 2 LAST CUSTOM_TXT_CDS <XR_PAGE_TITLE>
J 0
(5660 2350);
DISPLAY 0.638298 (5660 2350);
PAINT PINK (5660 2350);
DISPLAY INVISIBLE (5660 2350);
FORCEPROP 0 LAST CDS_CON_LAST_MODIFIED Thu Aug 24 16:13:54 2023
J 0
(11665 -2885);
PAINT MONO (11665 -2885);
DISPLAY INVISIBLE (11665 -2885);
FORCENOTE
THIS PAGE WAS INTENTIONALLY LEFT BLANK
(4550 525) 0;
DISPLAY LEFT (4550 525);
DISPLAY 4.914894 (4550 525);
FORCENOTE
20211026 MODIFY FOR GT
(4400 3450) 0;
DISPLAY LEFT (4400 3450);
DISPLAY 2.510638 (4400 3450);
PAINT PINK (4400 3450);
QUIT
